# T6G (Grand Teton) — schematic netlist excerpt (pin names and nets, part order shuffled) for the footprints in the layout excerpt that follows; sources: Cadence DE-HDL packaged netlist, KiCad conversion of 04192023_DAF0TMB3IC0_F0TG_MB_C_brd_V02_OCP.brd

PR389  Q_RES  1.5 1% EMPTY  pkg 0402LF  page 208 : A = SW_PVDD11_S3_P0_SW2_RC ; B = GND

U175  LTC4307CMS8  IC  pkg MSOP8  page 248
  ENABLE  = SMB_BMC_SWB_EN_R
  SCL_OUT  = SMB_BMC_SWB_BUF_R_SCL
  SCL_IN  = SMB_BMC_SWB_R_SCL
  GND  = GND
  READY  = NC
  SDA_IN  = SMB_BMC_SWB_R_SDA
  SDA_OUT  = SMB_BMC_SWB_BUF_R_SDA
  VCC  = P3V3_AUX

(kicad_pcb
	(version 20260206)
	(generator "pcbnew")
	(generator_version "10.0")
	(general
		(thickness 1.6)
		(legacy_teardrops no)
	)
	(paper "A4")
	(title_block
		(title "04192023_DAF0TMB3IC0_F0TG_MB_C_brd_V02_OCP.brd")
		(comment 1 "Grand Teton / footprints 1761-1762 of 8354")
	)
	(layers
		(0 "F.Cu" signal "TOP")
		(4 "In1.Cu" signal "GND")
		(6 "In2.Cu" signal "IN1")
		(8 "In3.Cu" signal "GND1")
		(10 "In4.Cu" signal "IN2")
		(12 "In5.Cu" signal "GND2")
		(14 "In6.Cu" signal "IN3")
		(16 "In7.Cu" signal "GND3")
		(18 "In8.Cu" signal "VCC")
		(20 "In9.Cu" signal "VCC1")
		(22 "In10.Cu" signal "GND4")
		(24 "In11.Cu" signal "IN4")
		(26 "In12.Cu" signal "GND5")
		(28 "In13.Cu" signal "IN5")
		(30 "In14.Cu" signal "GND6")
		(32 "In15.Cu" signal "IN6")
		(34 "In16.Cu" signal "GND7")
		(2 "B.Cu" signal "BOTTOM")
		(9 "F.Adhes" user "F.Adhesive")
		(11 "B.Adhes" user "B.Adhesive")
		(13 "F.Paste" user "Package Geometry/Pastemask Top")
		(15 "B.Paste" user "Package Geometry/Pastemask Bottom")
		(5 "F.SilkS" user "Ref Des/Silkscreen Top")
		(7 "B.SilkS" user "Ref Des/Silkscreen Bottom")
		(1 "F.Mask" user "Board Geometry/Soldermask Top")
		(3 "B.Mask" user "Board Geometry/Soldermask Bottom")
		(17 "Dwgs.User" user "User.Drawings")
		(19 "Cmts.User" user "User.Comments")
		(21 "Eco1.User" user "User.Eco1")
		(23 "Eco2.User" user "User.Eco2")
		(25 "Edge.Cuts" user "Board Geometry/Outline")
		(27 "Margin" user)
		(31 "F.CrtYd" user "Package Geometry/Place Bound Top")
		(29 "B.CrtYd" user "Package Geometry/Place Bound Bottom")
		(35 "F.Fab" user "Ref Des/Assembly Top")
		(33 "B.Fab" user "Ref Des/Assembly Bottom")
	)
	(footprint ""
		(layer "F.Cu")
		(at 163.250118 -432.04003 90)
		(property "Reference" "U175"
			(at -2.29743 5.584952 90)
			(unlocked yes)
			(layer "F.SilkS")
			(effects
				(font
					(size 0.7874 0.5842)
					(thickness 0.1524)
				)
				(justify left)
			)
		)
		(property "Value" ""
			(at 0 0 90)
			(layer "F.Fab")
			(effects
				(font
					(size 1.27 1.27)
				)
			)
		)
		(duplicate_pad_numbers_are_jumpers no)
		(fp_line
			(start 1.3716 -1.524)
			(end 1.3716 1.524)
			(stroke
				(width 0.1524)
				(type default)
			)
			(layer "F.SilkS")
		)
		(fp_line
			(start 0.508 -1.524)
			(end 1.3716 -1.524)
			(stroke
				(width 0.1524)
				(type default)
			)
			(layer "F.SilkS")
		)
		(fp_line
			(start -0.508 -1.524)
			(end 0 -1.016)
			(stroke
				(width 0.1524)
				(type default)
			)
			(layer "F.SilkS")
		)
		(fp_line
			(start -1.3716 -1.524)
			(end -0.508 -1.524)
			(stroke
				(width 0.1524)
				(type default)
			)
			(layer "F.SilkS")
		)
		(fp_line
			(start 0 -1.016)
			(end 0.508 -1.524)
			(stroke
				(width 0.1524)
				(type default)
			)
			(layer "F.SilkS")
		)
		(fp_line
			(start 1.3716 1.524)
			(end -1.3716 1.524)
			(stroke
				(width 0.1524)
				(type default)
			)
			(layer "F.SilkS")
		)
		(fp_line
			(start -1.3716 1.524)
			(end -1.3716 -1.524)
			(stroke
				(width 0.1524)
				(type default)
			)
			(layer "F.SilkS")
		)
		(fp_poly
			(pts
				(xy -3.60172 -0.719328) (xy -3.60172 -1.344168) (xy -3.048 -1.016)
			)
			(stroke
				(width 0)
				(type default)
			)
			(fill yes)
			(layer "F.SilkS")
		)
		(fp_line
			(start 1.5494 -1.524)
			(end 1.5494 -1.0668)
			(stroke
				(width 0.1)
				(type default)
			)
			(layer "F.Fab")
		)
		(fp_line
			(start -1.5494 -1.524)
			(end 1.5494 -1.524)
			(stroke
				(width 0.1)
				(type default)
			)
			(layer "F.Fab")
		)
		(fp_line
			(start 2.54 -1.0668)
			(end 2.54 1.0668)
			(stroke
				(width 0.1)
				(type default)
			)
			(layer "F.Fab")
		)
		(fp_line
			(start 1.5494 -1.0668)
			(end 2.54 -1.0668)
			(stroke
				(width 0.1)
				(type default)
			)
			(layer "F.Fab")
		)
		(fp_line
			(start 1.5494 -1.0668)
			(end 1.5494 1.0668)
			(stroke
				(width 0.1)
				(type default)
			)
			(layer "F.Fab")
		)
		(fp_line
			(start -1.5494 -1.0668)
			(end -1.5494 -1.524)
			(stroke
				(width 0.1)
				(type default)
			)
			(layer "F.Fab")
		)
		(fp_line
			(start -2.54 -1.0668)
			(end -1.5494 -1.0668)
			(stroke
				(width 0.1)
				(type default)
			)
			(layer "F.Fab")
		)
		(fp_line
			(start 2.54 1.0668)
			(end 1.5494 1.0668)
			(stroke
				(width 0.1)
				(type default)
			)
			(layer "F.Fab")
		)
		(fp_line
			(start 1.5494 1.0668)
			(end 1.5494 1.524)
			(stroke
				(width 0.1)
				(type default)
			)
			(layer "F.Fab")
		)
		(fp_line
			(start -1.5494 1.0668)
			(end -1.5494 -1.0668)
			(stroke
				(width 0.1)
				(type default)
			)
			(layer "F.Fab")
		)
		(fp_line
			(start -1.5494 1.0668)
			(end -2.54 1.0668)
			(stroke
				(width 0.1)
				(type default)
			)
			(layer "F.Fab")
		)
		(fp_line
			(start -2.54 1.0668)
			(end -2.54 -1.0668)
			(stroke
				(width 0.1)
				(type default)
			)
			(layer "F.Fab")
		)
		(fp_line
			(start 1.5494 1.524)
			(end -1.5494 1.524)
			(stroke
				(width 0.1)
				(type default)
			)
			(layer "F.Fab")
		)
		(fp_line
			(start -1.5494 1.524)
			(end -1.5494 1.0668)
			(stroke
				(width 0.1)
				(type default)
			)
			(layer "F.Fab")
		)
		(fp_poly
			(pts
				(xy -3.60172 -0.719328) (xy -3.60172 -1.344168) (xy -3.048 -1.016)
			)
			(stroke
				(width 0)
				(type default)
			)
			(fill yes)
			(layer "F.Fab")
		)
		(pad "1" smd rect
			(at -2.232406 -0.975106)
			(size 0.3556 1.4224)
			(layers "F.Cu" "F.Mask" "F.Paste")
			(net "SMB_BMC_SWB_EN_R")
		)
		(pad "2" smd rect
			(at -2.232406 -0.32512)
			(size 0.3556 1.4224)
			(layers "F.Cu" "F.Mask" "F.Paste")
			(net "SMB_BMC_SWB_BUF_R_SCL")
		)
		(pad "3" smd rect
			(at -2.232406 0.32512)
			(size 0.3556 1.4224)
			(layers "F.Cu" "F.Mask" "F.Paste")
			(net "SMB_BMC_SWB_R_SCL")
		)
		(pad "4" smd rect
			(at -2.232406 0.975106)
			(size 0.3556 1.4224)
			(layers "F.Cu" "F.Mask" "F.Paste")
			(net "GND")
		)
		(pad "5" smd rect
			(at 2.232406 0.975106)
			(size 0.3556 1.4224)
			(layers "F.Cu" "F.Mask" "F.Paste")
			(net "Net_10761")
		)
		(pad "6" smd rect
			(at 2.232406 0.32512)
			(size 0.3556 1.4224)
			(layers "F.Cu" "F.Mask" "F.Paste")
			(net "SMB_BMC_SWB_R_SDA")
		)
		(pad "7" smd rect
			(at 2.232406 -0.32512)
			(size 0.3556 1.4224)
			(layers "F.Cu" "F.Mask" "F.Paste")
			(net "SMB_BMC_SWB_BUF_R_SDA")
		)
		(pad "8" smd rect
			(at 2.232406 -0.975106)
			(size 0.3556 1.4224)
			(layers "F.Cu" "F.Mask" "F.Paste")
			(net "P3V3_AUX")
		)
	)
	(footprint ""
		(layer "F.Cu")
		(at 428.29353 -349.405956 90)
		(property "Reference" "PR389"
			(at 0 0 90)
			(layer "F.SilkS")
			(hide yes)
			(effects
				(font
					(size 1.27 1.27)
				)
			)
		)
		(property "Value" ""
			(at 0 0 90)
			(layer "F.Fab")
			(effects
				(font
					(size 1.27 1.27)
				)
			)
		)
		(duplicate_pad_numbers_are_jumpers no)
		(fp_line
			(start 0.7874 -0.4064)
			(end 0.7874 0.4064)
			(stroke
				(width 0.1524)
				(type default)
			)
			(layer "F.SilkS")
		)
		(fp_line
			(start -0.7874 -0.4064)
			(end 0.7874 -0.4064)
			(stroke
				(width 0.1524)
				(type default)
			)
			(layer "F.SilkS")
		)
		(fp_line
			(start 0.7874 0.4064)
			(end -0.7874 0.4064)
			(stroke
				(width 0.1524)
				(type default)
			)
			(layer "F.SilkS")
		)
		(fp_line
			(start -0.7874 0.4064)
			(end -0.7874 -0.4064)
			(stroke
				(width 0.1524)
				(type default)
			)
			(layer "F.SilkS")
		)
		(fp_line
			(start -0.12065 -0.305054)
			(end -0.12065 -0.2794)
			(stroke
				(width 0.1)
				(type default)
			)
			(layer "F.Fab")
		)
		(fp_line
			(start -0.67945 -0.305054)
			(end -0.12065 -0.305054)
			(stroke
				(width 0.1)
				(type default)
			)
			(layer "F.Fab")
		)
		(fp_line
			(start 0.67945 -0.3048)
			(end 0.67945 0.3048)
			(stroke
				(width 0.1)
				(type default)
			)
			(layer "F.Fab")
		)
		(fp_line
			(start 0.12065 -0.3048)
			(end 0.67945 -0.3048)
			(stroke
				(width 0.1)
				(type default)
			)
			(layer "F.Fab")
		)
		(fp_line
			(start 0.12065 -0.2794)
			(end 0.12065 -0.3048)
			(stroke
				(width 0.1)
				(type default)
			)
			(layer "F.Fab")
		)
		(fp_line
			(start -0.12065 -0.2794)
			(end 0.12065 -0.2794)
			(stroke
				(width 0.1)
				(type default)
			)
			(layer "F.Fab")
		)
		(fp_line
			(start 0.120396 0.2794)
			(end -0.12065 0.2794)
			(stroke
				(width 0.1)
				(type default)
			)
			(layer "F.Fab")
		)
		(fp_line
			(start -0.12065 0.2794)
			(end -0.12065 0.3048)
			(stroke
				(width 0.1)
				(type default)
			)
			(layer "F.Fab")
		)
		(fp_line
			(start 0.67945 0.3048)
			(end 0.120396 0.3048)
			(stroke
				(width 0.1)
				(type default)
			)
			(layer "F.Fab")
		)
		(fp_line
			(start 0.120396 0.3048)
			(end 0.120396 0.2794)
			(stroke
				(width 0.1)
				(type default)
			)
			(layer "F.Fab")
		)
		(fp_line
			(start -0.12065 0.3048)
			(end -0.67945 0.3048)
			(stroke
				(width 0.1)
				(type default)
			)
			(layer "F.Fab")
		)
		(fp_line
			(start -0.67945 0.3048)
			(end -0.67945 -0.305054)
			(stroke
				(width 0.1)
				(type default)
			)
			(layer "F.Fab")
		)
		(pad "1" smd circle
			(at -0.40005 0 90)
			(size 0 0)
			(layers "F.Cu" "F.Mask" "F.Paste")
			(net "SW_PVDD11_S3_P0_SW2_RC")
		)
		(pad "2" smd circle
			(at 0.40005 0 90)
			(size 0 0)
			(layers "F.Cu" "F.Mask" "F.Paste")
			(net "GND")
		)
	)
)
